FILE_TYPE = CONNECTIVITY;
{Allegro Design Entry HDL 17.2-2016 S081 (4005846) 1/11/2022}
"PAGE_NUMBER" = 259;
0"NC";
END.
